# T6G (Grand Teton) — schematic netlist excerpt (pin names and nets, part order shuffled) for the footprints in the layout excerpt that follows; sources: Cadence DE-HDL packaged netlist, KiCad conversion of 04192023_DAF0TMB3IC0_F0TG_MB_C_brd_V02_OCP.brd

C308  Q_CAP  10PF 50V 5% EMPTY  pkg 0402  page 217 : A = SVID_PVDDCR_CPU1_P1_SVTO ; B = GND
C6705  Q_CAP_DIFFBUS  DIFF BUS_0.22UF 6.3V 20% X6S  pkg C0201  page 341 : \1\ = P5E_CPU1_P2_TX_BUF_C_DP<6> ; \2\ = P5E_CPU1_P2_TX_BUF_DP<6>
R3429  Q_RES  100K 1% EMPTY  pkg 0402LF  page 126 : A = P3V3_AUX ; B = GPU_BASE_HMC_READY

(kicad_pcb
	(version 20260206)
	(generator "pcbnew")
	(generator_version "10.0")
	(general
		(thickness 1.6)
		(legacy_teardrops no)
	)
	(paper "A4")
	(title_block
		(title "04192023_DAF0TMB3IC0_F0TG_MB_C_brd_V02_OCP.brd")
		(comment 1 "Grand Teton / footprints 40-42 of 8354")
	)
	(layers
		(0 "F.Cu" signal "TOP")
		(4 "In1.Cu" signal "GND")
		(6 "In2.Cu" signal "IN1")
		(8 "In3.Cu" signal "GND1")
		(10 "In4.Cu" signal "IN2")
		(12 "In5.Cu" signal "GND2")
		(14 "In6.Cu" signal "IN3")
		(16 "In7.Cu" signal "GND3")
		(18 "In8.Cu" signal "VCC")
		(20 "In9.Cu" signal "VCC1")
		(22 "In10.Cu" signal "GND4")
		(24 "In11.Cu" signal "IN4")
		(26 "In12.Cu" signal "GND5")
		(28 "In13.Cu" signal "IN5")
		(30 "In14.Cu" signal "GND6")
		(32 "In15.Cu" signal "IN6")
		(34 "In16.Cu" signal "GND7")
		(2 "B.Cu" signal "BOTTOM")
		(9 "F.Adhes" user "F.Adhesive")
		(11 "B.Adhes" user "B.Adhesive")
		(13 "F.Paste" user "Package Geometry/Pastemask Top")
		(15 "B.Paste" user "Package Geometry/Pastemask Bottom")
		(5 "F.SilkS" user "Ref Des/Silkscreen Top")
		(7 "B.SilkS" user "Ref Des/Silkscreen Bottom")
		(1 "F.Mask" user "Board Geometry/Soldermask Top")
		(3 "B.Mask" user "Board Geometry/Soldermask Bottom")
		(17 "Dwgs.User" user "User.Drawings")
		(19 "Cmts.User" user "User.Comments")
		(21 "Eco1.User" user "User.Eco1")
		(23 "Eco2.User" user "User.Eco2")
		(25 "Edge.Cuts" user "Board Geometry/Outline")
		(27 "Margin" user)
		(31 "F.CrtYd" user "Package Geometry/Place Bound Top")
		(29 "B.CrtYd" user "Package Geometry/Place Bound Bottom")
		(35 "F.Fab" user "Ref Des/Assembly Top")
		(33 "B.Fab" user "Ref Des/Assembly Bottom")
	)
	(footprint ""
		(layer "F.Cu")
		(at 163.4236 -437.423052)
		(property "Reference" "R3429"
			(at 0 0 0)
			(layer "F.SilkS")
			(hide yes)
			(effects
				(font
					(size 1.27 1.27)
				)
			)
		)
		(property "Value" ""
			(at 0 0 0)
			(layer "F.Fab")
			(effects
				(font
					(size 1.27 1.27)
				)
			)
		)
		(duplicate_pad_numbers_are_jumpers no)
		(fp_line
			(start -0.7874 -0.4064)
			(end 0.7874 -0.4064)
			(stroke
				(width 0.1524)
				(type default)
			)
			(layer "F.SilkS")
		)
		(fp_line
			(start -0.7874 0.4064)
			(end -0.7874 -0.4064)
			(stroke
				(width 0.1524)
				(type default)
			)
			(layer "F.SilkS")
		)
		(fp_line
			(start 0.7874 -0.4064)
			(end 0.7874 0.4064)
			(stroke
				(width 0.1524)
				(type default)
			)
			(layer "F.SilkS")
		)
		(fp_line
			(start 0.7874 0.4064)
			(end -0.7874 0.4064)
			(stroke
				(width 0.1524)
				(type default)
			)
			(layer "F.SilkS")
		)
		(fp_line
			(start -0.67945 -0.305054)
			(end -0.12065 -0.305054)
			(stroke
				(width 0.1)
				(type default)
			)
			(layer "F.Fab")
		)
		(fp_line
			(start -0.67945 0.3048)
			(end -0.67945 -0.305054)
			(stroke
				(width 0.1)
				(type default)
			)
			(layer "F.Fab")
		)
		(fp_line
			(start -0.12065 -0.305054)
			(end -0.12065 -0.2794)
			(stroke
				(width 0.1)
				(type default)
			)
			(layer "F.Fab")
		)
		(fp_line
			(start -0.12065 -0.2794)
			(end 0.12065 -0.2794)
			(stroke
				(width 0.1)
				(type default)
			)
			(layer "F.Fab")
		)
		(fp_line
			(start -0.12065 0.2794)
			(end -0.12065 0.3048)
			(stroke
				(width 0.1)
				(type default)
			)
			(layer "F.Fab")
		)
		(fp_line
			(start -0.12065 0.3048)
			(end -0.67945 0.3048)
			(stroke
				(width 0.1)
				(type default)
			)
			(layer "F.Fab")
		)
		(fp_line
			(start 0.120396 0.2794)
			(end -0.12065 0.2794)
			(stroke
				(width 0.1)
				(type default)
			)
			(layer "F.Fab")
		)
		(fp_line
			(start 0.120396 0.3048)
			(end 0.120396 0.2794)
			(stroke
				(width 0.1)
				(type default)
			)
			(layer "F.Fab")
		)
		(fp_line
			(start 0.12065 -0.3048)
			(end 0.67945 -0.3048)
			(stroke
				(width 0.1)
				(type default)
			)
			(layer "F.Fab")
		)
		(fp_line
			(start 0.12065 -0.2794)
			(end 0.12065 -0.3048)
			(stroke
				(width 0.1)
				(type default)
			)
			(layer "F.Fab")
		)
		(fp_line
			(start 0.67945 -0.3048)
			(end 0.67945 0.3048)
			(stroke
				(width 0.1)
				(type default)
			)
			(layer "F.Fab")
		)
		(fp_line
			(start 0.67945 0.3048)
			(end 0.120396 0.3048)
			(stroke
				(width 0.1)
				(type default)
			)
			(layer "F.Fab")
		)
		(pad "1" smd circle
			(at -0.40005 0)
			(size 0 0)
			(layers "F.Cu" "F.Mask" "F.Paste")
			(net "P3V3_AUX")
		)
		(pad "2" smd circle
			(at 0.40005 0)
			(size 0 0)
			(layers "F.Cu" "F.Mask" "F.Paste")
			(net "GPU_BASE_HMC_READY")
		)
	)
	(footprint ""
		(layer "F.Cu")
		(at 134.162546 -408.517344 -90)
		(property "Reference" "C6705"
			(at 0 0 270)
			(layer "F.SilkS")
			(hide yes)
			(effects
				(font
					(size 1.27 1.27)
				)
			)
		)
		(property "Value" ""
			(at 0 0 270)
			(layer "F.Fab")
			(effects
				(font
					(size 1.27 1.27)
				)
			)
		)
		(duplicate_pad_numbers_are_jumpers no)
		(fp_line
			(start -0.299974 0.150114)
			(end -0.299974 -0.150114)
			(stroke
				(width 0.1)
				(type default)
			)
			(layer "F.Fab")
		)
		(fp_line
			(start 0.299974 0.150114)
			(end -0.299974 0.150114)
			(stroke
				(width 0.1)
				(type default)
			)
			(layer "F.Fab")
		)
		(fp_line
			(start -0.299974 -0.150114)
			(end 0.299974 -0.150114)
			(stroke
				(width 0.1)
				(type default)
			)
			(layer "F.Fab")
		)
		(fp_line
			(start 0.299974 -0.150114)
			(end 0.299974 0.150114)
			(stroke
				(width 0.1)
				(type default)
			)
			(layer "F.Fab")
		)
		(pad "1" smd rect
			(at -0.2667 0 270)
			(size 0.3048 0.381)
			(layers "F.Cu" "F.Mask" "F.Paste")
			(net "P5E_CPU1_P2_TX_BUF_C_DP<6>")
		)
		(pad "2" smd rect
			(at 0.2667 0 270)
			(size 0.3048 0.381)
			(layers "F.Cu" "F.Mask" "F.Paste")
			(net "P5E_CPU1_P2_TX_BUF_DP<6>")
		)
	)
	(footprint ""
		(layer "F.Cu")
		(at 22.479 -358.775 180)
		(property "Reference" "C308"
			(at 0 0 180)
			(layer "F.SilkS")
			(hide yes)
			(effects
				(font
					(size 1.27 1.27)
				)
			)
		)
		(property "Value" ""
			(at 0 0 180)
			(layer "F.Fab")
			(effects
				(font
					(size 1.27 1.27)
				)
			)
		)
		(duplicate_pad_numbers_are_jumpers no)
		(fp_line
			(start 0.7874 0.4064)
			(end -0.7874 0.4064)
			(stroke
				(width 0.1524)
				(type default)
			)
			(layer "F.SilkS")
		)
		(fp_line
			(start 0.7874 -0.4064)
			(end 0.7874 0.4064)
			(stroke
				(width 0.1524)
				(type default)
			)
			(layer "F.SilkS")
		)
		(fp_line
			(start -0.7874 0.4064)
			(end -0.7874 -0.4064)
			(stroke
				(width 0.1524)
				(type default)
			)
			(layer "F.SilkS")
		)
		(fp_line
			(start -0.7874 -0.4064)
			(end 0.7874 -0.4064)
			(stroke
				(width 0.1524)
				(type default)
			)
			(layer "F.SilkS")
		)
		(fp_line
			(start 0.67945 0.3048)
			(end 0.120396 0.3048)
			(stroke
				(width 0.1)
				(type default)
			)
			(layer "F.Fab")
		)
		(fp_line
			(start 0.67945 -0.3048)
			(end 0.67945 0.3048)
			(stroke
				(width 0.1)
				(type default)
			)
			(layer "F.Fab")
		)
		(fp_line
			(start 0.12065 -0.2794)
			(end 0.12065 -0.3048)
			(stroke
				(width 0.1)
				(type default)
			)
			(layer "F.Fab")
		)
		(fp_line
			(start 0.12065 -0.3048)
			(end 0.67945 -0.3048)
			(stroke
				(width 0.1)
				(type default)
			)
			(layer "F.Fab")
		)
		(fp_line
			(start 0.120396 0.3048)
			(end 0.120396 0.2794)
			(stroke
				(width 0.1)
				(type default)
			)
			(layer "F.Fab")
		)
		(fp_line
			(start 0.120396 0.2794)
			(end -0.12065 0.2794)
			(stroke
				(width 0.1)
				(type default)
			)
			(layer "F.Fab")
		)
		(fp_line
			(start -0.12065 0.3048)
			(end -0.67945 0.3048)
			(stroke
				(width 0.1)
				(type default)
			)
			(layer "F.Fab")
		)
		(fp_line
			(start -0.12065 0.2794)
			(end -0.12065 0.3048)
			(stroke
				(width 0.1)
				(type default)
			)
			(layer "F.Fab")
		)
		(fp_line
			(start -0.12065 -0.2794)
			(end 0.12065 -0.2794)
			(stroke
				(width 0.1)
				(type default)
			)
			(layer "F.Fab")
		)
		(fp_line
			(start -0.12065 -0.305054)
			(end -0.12065 -0.2794)
			(stroke
				(width 0.1)
				(type default)
			)
			(layer "F.Fab")
		)
		(fp_line
			(start -0.67945 0.3048)
			(end -0.67945 -0.305054)
			(stroke
				(width 0.1)
				(type default)
			)
			(layer "F.Fab")
		)
		(fp_line
			(start -0.67945 -0.305054)
			(end -0.12065 -0.305054)
			(stroke
				(width 0.1)
				(type default)
			)
			(layer "F.Fab")
		)
		(pad "1" smd circle
			(at -0.40005 0 180)
			(size 0 0)
			(layers "F.Cu" "F.Mask" "F.Paste")
			(net "SVID_PVDDCR_CPU1_P1_SVTO")
		)
		(pad "2" smd circle
			(at 0.40005 0 180)
			(size 0 0)
			(layers "F.Cu" "F.Mask" "F.Paste")
			(net "GND")
		)
	)
)
